(kicad_pcb
	(version 20260206)
	(generator "pcbnew")
	(generator_version "10.0")
	(general
		(thickness 1.6)
		(legacy_teardrops no)
	)
	(paper "A4")
	(title_block
		(title "01162023_DA0F0TEBIF0_F0T_Expander_BD_F_brd_V02_OCP.brd")
		(comment 1 "Grand Teton / footprints 2630-2636 of 9728")
	)
	(layers
		(0 "F.Cu" signal "TOP")
		(4 "In1.Cu" signal "GND")
		(6 "In2.Cu" signal "VCC")
		(8 "In3.Cu" signal "VCC1")
		(10 "In4.Cu" signal "GND1")
		(12 "In5.Cu" signal "IN1")
		(14 "In6.Cu" signal "GND2")
		(16 "In7.Cu" signal "IN2")
		(18 "In8.Cu" signal "GND3")
		(20 "In9.Cu" signal "IN3")
		(22 "In10.Cu" signal "GND4")
		(24 "In11.Cu" signal "IN4")
		(26 "In12.Cu" signal "GND5")
		(28 "In13.Cu" signal "IN5")
		(30 "In14.Cu" signal "GND6")
		(32 "In15.Cu" signal "IN6")
		(34 "In16.Cu" signal "GND7")
		(2 "B.Cu" signal "BOTTOM")
		(9 "F.Adhes" user "F.Adhesive")
		(11 "B.Adhes" user "B.Adhesive")
		(13 "F.Paste" user "Package Geometry/Pastemask Top")
		(15 "B.Paste" user "Package Geometry/Pastemask Bottom")
		(5 "F.SilkS" user "Ref Des/Silkscreen Top")
		(7 "B.SilkS" user "Ref Des/Silkscreen Bottom")
		(1 "F.Mask" user "Board Geometry/Soldermask Top")
		(3 "B.Mask" user "Board Geometry/Soldermask Bottom")
		(17 "Dwgs.User" user "User.Drawings")
		(19 "Cmts.User" user "User.Comments")
		(21 "Eco1.User" user "User.Eco1")
		(23 "Eco2.User" user "User.Eco2")
		(25 "Edge.Cuts" user "Board Geometry/Outline")
		(27 "Margin" user)
		(31 "F.CrtYd" user "Package Geometry/Place Bound Top")
		(29 "B.CrtYd" user "Package Geometry/Place Bound Bottom")
		(35 "F.Fab" user "Ref Des/Assembly Top")
		(33 "B.Fab" user "Ref Des/Assembly Bottom")
	)
	(footprint ""
		(layer "F.Cu")
		(at 378.18822 -257.64871 -90)
		(property "Reference" "C3559"
			(at 0 0 270)
			(layer "F.SilkS")
			(hide yes)
			(effects
				(font
					(size 1.27 1.27)
				)
			)
		)
		(property "Value" ""
			(at 0 0 270)
			(layer "F.Fab")
			(effects
				(font
					(size 1.27 1.27)
				)
			)
		)
		(duplicate_pad_numbers_are_jumpers no)
		(fp_line
			(start -1.2954 0.5842)
			(end -1.2954 -0.5842)
			(stroke
				(width 0.1524)
				(type default)
			)
			(layer "F.SilkS")
		)
		(fp_line
			(start 1.2954 0.5842)
			(end -1.2954 0.5842)
			(stroke
				(width 0.1524)
				(type default)
			)
			(layer "F.SilkS")
		)
		(fp_line
			(start -1.2954 -0.5842)
			(end 1.2954 -0.5842)
			(stroke
				(width 0.1524)
				(type default)
			)
			(layer "F.SilkS")
		)
		(fp_line
			(start 1.2954 -0.5842)
			(end 1.2954 0.5842)
			(stroke
				(width 0.1524)
				(type default)
			)
			(layer "F.SilkS")
		)
		(fp_line
			(start -0.8636 0.4572)
			(end -0.8636 0.4064)
			(stroke
				(width 0.1)
				(type default)
			)
			(layer "F.Fab")
		)
		(fp_line
			(start 0.8636 0.4572)
			(end -0.8636 0.4572)
			(stroke
				(width 0.1)
				(type default)
			)
			(layer "F.Fab")
		)
		(fp_line
			(start -1.1938 0.4064)
			(end -1.1938 -0.4064)
			(stroke
				(width 0.1)
				(type default)
			)
			(layer "F.Fab")
		)
		(fp_line
			(start -0.8636 0.4064)
			(end -1.1938 0.4064)
			(stroke
				(width 0.1)
				(type default)
			)
			(layer "F.Fab")
		)
		(fp_line
			(start 0.8636 0.4064)
			(end 0.8636 0.4572)
			(stroke
				(width 0.1)
				(type default)
			)
			(layer "F.Fab")
		)
		(fp_line
			(start 1.1938 0.4064)
			(end 0.8636 0.4064)
			(stroke
				(width 0.1)
				(type default)
			)
			(layer "F.Fab")
		)
		(fp_line
			(start -1.1938 -0.4064)
			(end -0.8636 -0.4064)
			(stroke
				(width 0.1)
				(type default)
			)
			(layer "F.Fab")
		)
		(fp_line
			(start -0.8636 -0.4064)
			(end -0.8636 -0.4572)
			(stroke
				(width 0.1)
				(type default)
			)
			(layer "F.Fab")
		)
		(fp_line
			(start 0.8636 -0.4064)
			(end 1.1938 -0.4064)
			(stroke
				(width 0.1)
				(type default)
			)
			(layer "F.Fab")
		)
		(fp_line
			(start 1.1938 -0.4064)
			(end 1.1938 0.4064)
			(stroke
				(width 0.1)
				(type default)
			)
			(layer "F.Fab")
		)
		(fp_line
			(start -0.8636 -0.4572)
			(end 0.8636 -0.4572)
			(stroke
				(width 0.1)
				(type default)
			)
			(layer "F.Fab")
		)
		(fp_line
			(start 0.8636 -0.4572)
			(end 0.8636 -0.4064)
			(stroke
				(width 0.1)
				(type default)
			)
			(layer "F.Fab")
		)
		(pad "1" smd rect
			(at -0.7366 0 180)
			(size 0.7112 0.8128)
			(layers "F.Cu" "F.Mask" "F.Paste")
			(net "P1V8_PLL0_PEX3")
		)
		(pad "2" smd rect
			(at 0.7366 0 180)
			(size 0.7112 0.8128)
			(layers "F.Cu" "F.Mask" "F.Paste")
			(net "GND")
		)
	)
	(footprint ""
		(layer "F.Cu")
		(at 430.450498 -80.581246 90)
		(property "Reference" "U47"
			(at -0.672846 2.366772 90)
			(unlocked yes)
			(layer "F.SilkS")
			(effects
				(font
					(size 0.7874 0.5842)
					(thickness 0.1524)
				)
			)
		)
		(property "Value" ""
			(at 0 0 90)
			(layer "F.Fab")
			(effects
				(font
					(size 1.27 1.27)
				)
			)
		)
		(duplicate_pad_numbers_are_jumpers no)
		(fp_line
			(start 1.905 -1.651)
			(end 1.905 1.651)
			(stroke
				(width 0.1524)
				(type default)
			)
			(layer "F.SilkS")
		)
		(fp_line
			(start -1.905 -1.651)
			(end 1.905 -1.651)
			(stroke
				(width 0.1524)
				(type default)
			)
			(layer "F.SilkS")
		)
		(fp_line
			(start 1.905 1.651)
			(end -1.905 1.651)
			(stroke
				(width 0.1524)
				(type default)
			)
			(layer "F.SilkS")
		)
		(fp_line
			(start -1.905 1.651)
			(end -1.905 -1.651)
			(stroke
				(width 0.1524)
				(type default)
			)
			(layer "F.SilkS")
		)
		(fp_line
			(start 0.6985 -1.524)
			(end 0.6985 -0.219964)
			(stroke
				(width 0.1)
				(type default)
			)
			(layer "F.Fab")
		)
		(fp_line
			(start -0.649986 -1.524)
			(end 0.6985 -1.524)
			(stroke
				(width 0.1)
				(type default)
			)
			(layer "F.Fab")
		)
		(fp_line
			(start -0.649986 -1.169924)
			(end -0.649986 -1.524)
			(stroke
				(width 0.1)
				(type default)
			)
			(layer "F.Fab")
		)
		(fp_line
			(start -1.249934 -1.169924)
			(end -0.649986 -1.169924)
			(stroke
				(width 0.1)
				(type default)
			)
			(layer "F.Fab")
		)
		(fp_line
			(start -0.6985 -0.729996)
			(end -1.249934 -0.729996)
			(stroke
				(width 0.1)
				(type default)
			)
			(layer "F.Fab")
		)
		(fp_line
			(start -1.249934 -0.729996)
			(end -1.249934 -1.169924)
			(stroke
				(width 0.1)
				(type default)
			)
			(layer "F.Fab")
		)
		(fp_line
			(start 1.249934 -0.219964)
			(end 1.249934 0.219964)
			(stroke
				(width 0.1)
				(type default)
			)
			(layer "F.Fab")
		)
		(fp_line
			(start 0.6985 -0.219964)
			(end 1.249934 -0.219964)
			(stroke
				(width 0.1)
				(type default)
			)
			(layer "F.Fab")
		)
		(fp_line
			(start 1.249934 0.219964)
			(end 0.6985 0.219964)
			(stroke
				(width 0.1)
				(type default)
			)
			(layer "F.Fab")
		)
		(fp_line
			(start 0.6985 0.219964)
			(end 0.6985 1.524)
			(stroke
				(width 0.1)
				(type default)
			)
			(layer "F.Fab")
		)
		(fp_line
			(start -0.6985 0.729996)
			(end -0.6985 -0.729996)
			(stroke
				(width 0.1)
				(type default)
			)
			(layer "F.Fab")
		)
		(fp_line
			(start -1.249934 0.729996)
			(end -0.6985 0.729996)
			(stroke
				(width 0.1)
				(type default)
			)
			(layer "F.Fab")
		)
		(fp_line
			(start -0.649986 1.169924)
			(end -1.249934 1.169924)
			(stroke
				(width 0.1)
				(type default)
			)
			(layer "F.Fab")
		)
		(fp_line
			(start -1.249934 1.169924)
			(end -1.249934 0.729996)
			(stroke
				(width 0.1)
				(type default)
			)
			(layer "F.Fab")
		)
		(fp_line
			(start 0.6985 1.524)
			(end -0.649986 1.524)
			(stroke
				(width 0.1)
				(type default)
			)
			(layer "F.Fab")
		)
		(fp_line
			(start -0.649986 1.524)
			(end -0.649986 1.169924)
			(stroke
				(width 0.1)
				(type default)
			)
			(layer "F.Fab")
		)
		(pad "1" smd rect
			(at -1.1176 -1.016)
			(size 1.016 1.27)
			(layers "F.Cu" "F.Mask" "F.Paste")
			(net "HP_NIC7_PWRGD")
		)
		(pad "2" smd rect
			(at -1.1176 1.016)
			(size 1.016 1.27)
			(layers "F.Cu" "F.Mask" "F.Paste")
			(net "P3V3_NIC7")
		)
		(pad "3" smd rect
			(at 1.1176 0)
			(size 1.016 1.27)
			(layers "F.Cu" "F.Mask" "F.Paste")
			(net "GND")
		)
	)
	(footprint ""
		(layer "F.Cu")
		(at 221.211902 -139.641834)
		(property "Reference" "R4219"
			(at 0 0 0)
			(layer "F.SilkS")
			(hide yes)
			(effects
				(font
					(size 1.27 1.27)
				)
			)
		)
		(property "Value" ""
			(at 0 0 0)
			(layer "F.Fab")
			(effects
				(font
					(size 1.27 1.27)
				)
			)
		)
		(duplicate_pad_numbers_are_jumpers no)
		(fp_line
			(start -0.7874 -0.4064)
			(end 0.7874 -0.4064)
			(stroke
				(width 0.1524)
				(type default)
			)
			(layer "F.SilkS")
		)
		(fp_line
			(start -0.7874 0.4064)
			(end -0.7874 -0.4064)
			(stroke
				(width 0.1524)
				(type default)
			)
			(layer "F.SilkS")
		)
		(fp_line
			(start 0.7874 -0.4064)
			(end 0.7874 0.4064)
			(stroke
				(width 0.1524)
				(type default)
			)
			(layer "F.SilkS")
		)
		(fp_line
			(start 0.7874 0.4064)
			(end -0.7874 0.4064)
			(stroke
				(width 0.1524)
				(type default)
			)
			(layer "F.SilkS")
		)
		(fp_line
			(start -0.67945 -0.305054)
			(end -0.12065 -0.305054)
			(stroke
				(width 0.1)
				(type default)
			)
			(layer "F.Fab")
		)
		(fp_line
			(start -0.67945 0.3048)
			(end -0.67945 -0.305054)
			(stroke
				(width 0.1)
				(type default)
			)
			(layer "F.Fab")
		)
		(fp_line
			(start -0.12065 -0.305054)
			(end -0.12065 -0.2794)
			(stroke
				(width 0.1)
				(type default)
			)
			(layer "F.Fab")
		)
		(fp_line
			(start -0.12065 -0.2794)
			(end 0.12065 -0.2794)
			(stroke
				(width 0.1)
				(type default)
			)
			(layer "F.Fab")
		)
		(fp_line
			(start -0.12065 0.2794)
			(end -0.12065 0.3048)
			(stroke
				(width 0.1)
				(type default)
			)
			(layer "F.Fab")
		)
		(fp_line
			(start -0.12065 0.3048)
			(end -0.67945 0.3048)
			(stroke
				(width 0.1)
				(type default)
			)
			(layer "F.Fab")
		)
		(fp_line
			(start 0.120396 0.2794)
			(end -0.12065 0.2794)
			(stroke
				(width 0.1)
				(type default)
			)
			(layer "F.Fab")
		)
		(fp_line
			(start 0.120396 0.3048)
			(end 0.120396 0.2794)
			(stroke
				(width 0.1)
				(type default)
			)
			(layer "F.Fab")
		)
		(fp_line
			(start 0.12065 -0.3048)
			(end 0.67945 -0.3048)
			(stroke
				(width 0.1)
				(type default)
			)
			(layer "F.Fab")
		)
		(fp_line
			(start 0.12065 -0.2794)
			(end 0.12065 -0.3048)
			(stroke
				(width 0.1)
				(type default)
			)
			(layer "F.Fab")
		)
		(fp_line
			(start 0.67945 -0.3048)
			(end 0.67945 0.3048)
			(stroke
				(width 0.1)
				(type default)
			)
			(layer "F.Fab")
		)
		(fp_line
			(start 0.67945 0.3048)
			(end 0.120396 0.3048)
			(stroke
				(width 0.1)
				(type default)
			)
			(layer "F.Fab")
		)
		(pad "1" smd circle
			(at -0.40005 0)
			(size 0 0)
			(layers "F.Cu" "F.Mask" "F.Paste")
			(net "P3V3")
		)
		(pad "2" smd circle
			(at 0.40005 0)
			(size 0 0)
			(layers "F.Cu" "F.Mask" "F.Paste")
			(net "PU_CK440_PEX_PFT_LOST_N")
		)
	)
	(footprint ""
		(layer "F.Cu")
		(at 58.0644 -139.6238)
		(property "Reference" "R37"
			(at 0 0 0)
			(layer "F.SilkS")
			(hide yes)
			(effects
				(font
					(size 1.27 1.27)
				)
			)
		)
		(property "Value" ""
			(at 0 0 0)
			(layer "F.Fab")
			(effects
				(font
					(size 1.27 1.27)
				)
			)
		)
		(duplicate_pad_numbers_are_jumpers no)
		(fp_line
			(start -0.7874 -0.4064)
			(end 0.7874 -0.4064)
			(stroke
				(width 0.1524)
				(type default)
			)
			(layer "F.SilkS")
		)
		(fp_line
			(start -0.7874 0.4064)
			(end -0.7874 -0.4064)
			(stroke
				(width 0.1524)
				(type default)
			)
			(layer "F.SilkS")
		)
		(fp_line
			(start 0.7874 -0.4064)
			(end 0.7874 0.4064)
			(stroke
				(width 0.1524)
				(type default)
			)
			(layer "F.SilkS")
		)
		(fp_line
			(start 0.7874 0.4064)
			(end -0.7874 0.4064)
			(stroke
				(width 0.1524)
				(type default)
			)
			(layer "F.SilkS")
		)
		(fp_line
			(start -0.67945 -0.305054)
			(end -0.12065 -0.305054)
			(stroke
				(width 0.1)
				(type default)
			)
			(layer "F.Fab")
		)
		(fp_line
			(start -0.67945 0.3048)
			(end -0.67945 -0.305054)
			(stroke
				(width 0.1)
				(type default)
			)
			(layer "F.Fab")
		)
		(fp_line
			(start -0.12065 -0.305054)
			(end -0.12065 -0.2794)
			(stroke
				(width 0.1)
				(type default)
			)
			(layer "F.Fab")
		)
		(fp_line
			(start -0.12065 -0.2794)
			(end 0.12065 -0.2794)
			(stroke
				(width 0.1)
				(type default)
			)
			(layer "F.Fab")
		)
		(fp_line
			(start -0.12065 0.2794)
			(end -0.12065 0.3048)
			(stroke
				(width 0.1)
				(type default)
			)
			(layer "F.Fab")
		)
		(fp_line
			(start -0.12065 0.3048)
			(end -0.67945 0.3048)
			(stroke
				(width 0.1)
				(type default)
			)
			(layer "F.Fab")
		)
		(fp_line
			(start 0.120396 0.2794)
			(end -0.12065 0.2794)
			(stroke
				(width 0.1)
				(type default)
			)
			(layer "F.Fab")
		)
		(fp_line
			(start 0.120396 0.3048)
			(end 0.120396 0.2794)
			(stroke
				(width 0.1)
				(type default)
			)
			(layer "F.Fab")
		)
		(fp_line
			(start 0.12065 -0.3048)
			(end 0.67945 -0.3048)
			(stroke
				(width 0.1)
				(type default)
			)
			(layer "F.Fab")
		)
		(fp_line
			(start 0.12065 -0.2794)
			(end 0.12065 -0.3048)
			(stroke
				(width 0.1)
				(type default)
			)
			(layer "F.Fab")
		)
		(fp_line
			(start 0.67945 -0.3048)
			(end 0.67945 0.3048)
			(stroke
				(width 0.1)
				(type default)
			)
			(layer "F.Fab")
		)
		(fp_line
			(start 0.67945 0.3048)
			(end 0.120396 0.3048)
			(stroke
				(width 0.1)
				(type default)
			)
			(layer "F.Fab")
		)
		(pad "1" smd circle
			(at -0.40005 0)
			(size 0 0)
			(layers "F.Cu" "F.Mask" "F.Paste")
			(net "RST_SMB_NIC0_MUX_ISO_R_N")
		)
		(pad "2" smd circle
			(at 0.40005 0)
			(size 0 0)
			(layers "F.Cu" "F.Mask" "F.Paste")
			(net "RST_SMB_NIC0_MUX_ISO_N")
		)
	)
	(footprint ""
		(layer "F.Cu")
		(at 270.960342 -96.1644)
		(property "Reference" "R246"
			(at 0 0 0)
			(layer "F.SilkS")
			(hide yes)
			(effects
				(font
					(size 1.27 1.27)
				)
			)
		)
		(property "Value" ""
			(at 0 0 0)
			(layer "F.Fab")
			(effects
				(font
					(size 1.27 1.27)
				)
			)
		)
		(duplicate_pad_numbers_are_jumpers no)
		(fp_line
			(start -0.7874 -0.4064)
			(end 0.7874 -0.4064)
			(stroke
				(width 0.1524)
				(type default)
			)
			(layer "F.SilkS")
		)
		(fp_line
			(start -0.7874 0.4064)
			(end -0.7874 -0.4064)
			(stroke
				(width 0.1524)
				(type default)
			)
			(layer "F.SilkS")
		)
		(fp_line
			(start 0.7874 -0.4064)
			(end 0.7874 0.4064)
			(stroke
				(width 0.1524)
				(type default)
			)
			(layer "F.SilkS")
		)
		(fp_line
			(start 0.7874 0.4064)
			(end -0.7874 0.4064)
			(stroke
				(width 0.1524)
				(type default)
			)
			(layer "F.SilkS")
		)
		(fp_line
			(start -0.67945 -0.305054)
			(end -0.12065 -0.305054)
			(stroke
				(width 0.1)
				(type default)
			)
			(layer "F.Fab")
		)
		(fp_line
			(start -0.67945 0.3048)
			(end -0.67945 -0.305054)
			(stroke
				(width 0.1)
				(type default)
			)
			(layer "F.Fab")
		)
		(fp_line
			(start -0.12065 -0.305054)
			(end -0.12065 -0.2794)
			(stroke
				(width 0.1)
				(type default)
			)
			(layer "F.Fab")
		)
		(fp_line
			(start -0.12065 -0.2794)
			(end 0.12065 -0.2794)
			(stroke
				(width 0.1)
				(type default)
			)
			(layer "F.Fab")
		)
		(fp_line
			(start -0.12065 0.2794)
			(end -0.12065 0.3048)
			(stroke
				(width 0.1)
				(type default)
			)
			(layer "F.Fab")
		)
		(fp_line
			(start -0.12065 0.3048)
			(end -0.67945 0.3048)
			(stroke
				(width 0.1)
				(type default)
			)
			(layer "F.Fab")
		)
		(fp_line
			(start 0.120396 0.2794)
			(end -0.12065 0.2794)
			(stroke
				(width 0.1)
				(type default)
			)
			(layer "F.Fab")
		)
		(fp_line
			(start 0.120396 0.3048)
			(end 0.120396 0.2794)
			(stroke
				(width 0.1)
				(type default)
			)
			(layer "F.Fab")
		)
		(fp_line
			(start 0.12065 -0.3048)
			(end 0.67945 -0.3048)
			(stroke
				(width 0.1)
				(type default)
			)
			(layer "F.Fab")
		)
		(fp_line
			(start 0.12065 -0.2794)
			(end 0.12065 -0.3048)
			(stroke
				(width 0.1)
				(type default)
			)
			(layer "F.Fab")
		)
		(fp_line
			(start 0.67945 -0.3048)
			(end 0.67945 0.3048)
			(stroke
				(width 0.1)
				(type default)
			)
			(layer "F.Fab")
		)
		(fp_line
			(start 0.67945 0.3048)
			(end 0.120396 0.3048)
			(stroke
				(width 0.1)
				(type default)
			)
			(layer "F.Fab")
		)
		(pad "1" smd circle
			(at -0.40005 0)
			(size 0 0)
			(layers "F.Cu" "F.Mask" "F.Paste")
			(net "PRSNT_NIC4_N")
		)
		(pad "2" smd circle
			(at 0.40005 0)
			(size 0 0)
			(layers "F.Cu" "F.Mask" "F.Paste")
			(net "PRSNTB3_NIC4_N")
		)
	)
	(footprint ""
		(layer "F.Cu")
		(at 384.938524 -105.609898)
		(property "Reference" "C691"
			(at 0 0 0)
			(layer "F.SilkS")
			(hide yes)
			(effects
				(font
					(size 1.27 1.27)
				)
			)
		)
		(property "Value" ""
			(at 0 0 0)
			(layer "F.Fab")
			(effects
				(font
					(size 1.27 1.27)
				)
			)
		)
		(duplicate_pad_numbers_are_jumpers no)
		(fp_line
			(start -0.299974 -0.150114)
			(end 0.299974 -0.150114)
			(stroke
				(width 0.1)
				(type default)
			)
			(layer "F.Fab")
		)
		(fp_line
			(start -0.299974 0.150114)
			(end -0.299974 -0.150114)
			(stroke
				(width 0.1)
				(type default)
			)
			(layer "F.Fab")
		)
		(fp_line
			(start 0.299974 -0.150114)
			(end 0.299974 0.150114)
			(stroke
				(width 0.1)
				(type default)
			)
			(layer "F.Fab")
		)
		(fp_line
			(start 0.299974 0.150114)
			(end -0.299974 0.150114)
			(stroke
				(width 0.1)
				(type default)
			)
			(layer "F.Fab")
		)
		(pad "1" smd rect
			(at -0.2667 0)
			(size 0.3048 0.381)
			(layers "F.Cu" "F.Mask" "F.Paste")
			(net "P5E_PEX3_STN1_TX_DP<19>")
		)
		(pad "2" smd rect
			(at 0.2667 0)
			(size 0.3048 0.381)
			(layers "F.Cu" "F.Mask" "F.Paste")
			(net "P5E_PEX3_STN1_TX_C_DP<19>")
		)
	)
	(footprint ""
		(layer "F.Cu")
		(at 394.959586 -61.612526)
		(property "Reference" "PD45"
			(at -3.7084 -2.733548 0)
			(unlocked yes)
			(layer "F.SilkS")
			(effects
				(font
					(size 0.7874 0.5842)
					(thickness 0.1524)
				)
				(justify left)
			)
		)
		(property "Value" ""
			(at 0 0 0)
			(layer "F.Fab")
			(effects
				(font
					(size 1.27 1.27)
				)
			)
		)
		(duplicate_pad_numbers_are_jumpers no)
		(fp_line
			(start -3.656584 -1.970024)
			(end -3.656584 1.970024)
			(stroke
				(width 0.1524)
				(type default)
			)
			(layer "F.SilkS")
		)
		(fp_line
			(start -3.656584 1.970024)
			(end 4.240784 1.970024)
			(stroke
				(width 0.1524)
				(type default)
			)
			(layer "F.SilkS")
		)
		(fp_line
			(start 4.240784 -1.970024)
			(end -3.656584 -1.970024)
			(stroke
				(width 0.1524)
				(type default)
			)
			(layer "F.SilkS")
		)
		(fp_line
			(start 4.240784 1.970024)
			(end 4.240784 -1.970024)
			(stroke
				(width 0.1524)
				(type default)
			)
			(layer "F.SilkS")
		)
		(fp_poly
			(pts
				(xy 3.580384 1.970024) (xy 3.580384 -1.970024) (xy 4.240784 -1.970024) (xy 4.240784 1.970024)
			)
			(stroke
				(width 0)
				(type default)
			)
			(fill yes)
			(layer "F.SilkS")
		)
		(fp_line
			(start -2.3749 -1.970024)
			(end -2.3749 1.970024)
			(stroke
				(width 0.1)
				(type default)
			)
			(layer "F.Fab")
		)
		(fp_line
			(start -2.3749 1.970024)
			(end 2.3749 1.970024)
			(stroke
				(width 0.1)
				(type default)
			)
			(layer "F.Fab")
		)
		(fp_line
			(start 2.3749 -1.970024)
			(end -2.3749 -1.970024)
			(stroke
				(width 0.1)
				(type default)
			)
			(layer "F.Fab")
		)
		(fp_line
			(start 2.3749 1.970024)
			(end 2.3749 -1.970024)
			(stroke
				(width 0.1)
				(type default)
			)
			(layer "F.Fab")
		)
		(fp_text user "+"
			(at -4.9784 -0.23495 0)
			(unlocked yes)
			(layer "F.Fab")
			(effects
				(font
					(size 1.905 1.4224)
					(thickness 0.1524)
				)
				(justify left)
			)
		)
		(fp_text user "-"
			(at 4.1656 -0.23495 0)
			(unlocked yes)
			(layer "F.Fab")
			(effects
				(font
					(size 1.905 1.4224)
					(thickness 0.1524)
				)
				(justify left)
			)
		)
		(pad "A" smd rect
			(at -2.450084 0)
			(size 2.159 2.2606)
			(layers "F.Cu" "F.Mask" "F.Paste")
			(net "GND")
		)
		(pad "C" smd rect
			(at 2.450084 0)
			(size 2.159 2.2606)
			(layers "F.Cu" "F.Mask" "F.Paste")
			(net "P12V_AUX")
		)
	)
)
